(kicad_pcb
	(version 20260206)
	(generator "pcbnew")
	(generator_version "10.0")
	(general
		(thickness 1.6)
		(legacy_teardrops no)
	)
	(paper "A4")
	(title_block
		(title "03242023_DA0F0TMBIJ0_F0T_Motherboard_J_brd_V01_OCP.brd")
		(comment 1 "Grand Teton / footprints 3834-3837 of 6105")
	)
	(layers
		(0 "F.Cu" signal "TOP")
		(4 "In1.Cu" signal "GND")
		(6 "In2.Cu" signal "IN1")
		(8 "In3.Cu" signal "GND1")
		(10 "In4.Cu" signal "IN2")
		(12 "In5.Cu" signal "GND2")
		(14 "In6.Cu" signal "IN3")
		(16 "In7.Cu" signal "GND3")
		(18 "In8.Cu" signal "VCC")
		(20 "In9.Cu" signal "VCC1")
		(22 "In10.Cu" signal "GND4")
		(24 "In11.Cu" signal "IN4")
		(26 "In12.Cu" signal "GND5")
		(28 "In13.Cu" signal "IN5")
		(30 "In14.Cu" signal "GND6")
		(32 "In15.Cu" signal "IN6")
		(34 "In16.Cu" signal "GND7")
		(2 "B.Cu" signal "BOTTOM")
		(9 "F.Adhes" user "F.Adhesive")
		(11 "B.Adhes" user "B.Adhesive")
		(13 "F.Paste" user "Package Geometry/Pastemask Top")
		(15 "B.Paste" user "Package Geometry/Pastemask Bottom")
		(5 "F.SilkS" user "Ref Des/Silkscreen Top")
		(7 "B.SilkS" user "Ref Des/Silkscreen Bottom")
		(1 "F.Mask" user "Board Geometry/Soldermask Top")
		(3 "B.Mask" user "Board Geometry/Soldermask Bottom")
		(17 "Dwgs.User" user "User.Drawings")
		(19 "Cmts.User" user "User.Comments")
		(21 "Eco1.User" user "User.Eco1")
		(23 "Eco2.User" user "User.Eco2")
		(25 "Edge.Cuts" user "Board Geometry/Outline")
		(27 "Margin" user)
		(31 "F.CrtYd" user "Package Geometry/Place Bound Top")
		(29 "B.CrtYd" user "Package Geometry/Place Bound Bottom")
		(35 "F.Fab" user "Ref Des/Assembly Top")
		(33 "B.Fab" user "Ref Des/Assembly Bottom")
	)
	(footprint ""
		(layer "F.Cu")
		(at 292.19398 -53.652674)
		(property "Reference" "R4074"
			(at 0 0 0)
			(layer "F.SilkS")
			(hide yes)
			(effects
				(font
					(size 1.27 1.27)
				)
			)
		)
		(property "Value" ""
			(at 0 0 0)
			(layer "F.Fab")
			(effects
				(font
					(size 1.27 1.27)
				)
			)
		)
		(duplicate_pad_numbers_are_jumpers no)
		(fp_line
			(start -0.7874 -0.4064)
			(end 0.7874 -0.4064)
			(stroke
				(width 0.1524)
				(type default)
			)
			(layer "F.SilkS")
		)
		(fp_line
			(start -0.7874 0.4064)
			(end -0.7874 -0.4064)
			(stroke
				(width 0.1524)
				(type default)
			)
			(layer "F.SilkS")
		)
		(fp_line
			(start 0.7874 -0.4064)
			(end 0.7874 0.4064)
			(stroke
				(width 0.1524)
				(type default)
			)
			(layer "F.SilkS")
		)
		(fp_line
			(start 0.7874 0.4064)
			(end -0.7874 0.4064)
			(stroke
				(width 0.1524)
				(type default)
			)
			(layer "F.SilkS")
		)
		(fp_line
			(start -0.67945 -0.305054)
			(end -0.12065 -0.305054)
			(stroke
				(width 0.1)
				(type default)
			)
			(layer "F.Fab")
		)
		(fp_line
			(start -0.67945 0.3048)
			(end -0.67945 -0.305054)
			(stroke
				(width 0.1)
				(type default)
			)
			(layer "F.Fab")
		)
		(fp_line
			(start -0.12065 -0.305054)
			(end -0.12065 -0.2794)
			(stroke
				(width 0.1)
				(type default)
			)
			(layer "F.Fab")
		)
		(fp_line
			(start -0.12065 -0.2794)
			(end 0.12065 -0.2794)
			(stroke
				(width 0.1)
				(type default)
			)
			(layer "F.Fab")
		)
		(fp_line
			(start -0.12065 0.2794)
			(end -0.12065 0.3048)
			(stroke
				(width 0.1)
				(type default)
			)
			(layer "F.Fab")
		)
		(fp_line
			(start -0.12065 0.3048)
			(end -0.67945 0.3048)
			(stroke
				(width 0.1)
				(type default)
			)
			(layer "F.Fab")
		)
		(fp_line
			(start 0.120396 0.2794)
			(end -0.12065 0.2794)
			(stroke
				(width 0.1)
				(type default)
			)
			(layer "F.Fab")
		)
		(fp_line
			(start 0.120396 0.3048)
			(end 0.120396 0.2794)
			(stroke
				(width 0.1)
				(type default)
			)
			(layer "F.Fab")
		)
		(fp_line
			(start 0.12065 -0.3048)
			(end 0.67945 -0.3048)
			(stroke
				(width 0.1)
				(type default)
			)
			(layer "F.Fab")
		)
		(fp_line
			(start 0.12065 -0.2794)
			(end 0.12065 -0.3048)
			(stroke
				(width 0.1)
				(type default)
			)
			(layer "F.Fab")
		)
		(fp_line
			(start 0.67945 -0.3048)
			(end 0.67945 0.3048)
			(stroke
				(width 0.1)
				(type default)
			)
			(layer "F.Fab")
		)
		(fp_line
			(start 0.67945 0.3048)
			(end 0.120396 0.3048)
			(stroke
				(width 0.1)
				(type default)
			)
			(layer "F.Fab")
		)
		(pad "1" smd circle
			(at -0.40005 0)
			(size 0 0)
			(layers "F.Cu" "F.Mask" "F.Paste")
			(net "P12V_AUX")
		)
		(pad "2" smd circle
			(at 0.40005 0)
			(size 0 0)
			(layers "F.Cu" "F.Mask" "F.Paste")
			(net "P12V_E1S_0_EN_G")
		)
	)
	(footprint ""
		(layer "F.Cu")
		(at 416.160458 -362.087668)
		(property "Reference" "PU69_P0_1"
			(at -7.134098 -6.55193 0)
			(unlocked yes)
			(layer "F.SilkS")
			(effects
				(font
					(size 0.7874 0.5842)
					(thickness 0.1524)
				)
				(justify left)
			)
		)
		(property "Value" ""
			(at 0 0 0)
			(layer "F.Fab")
			(effects
				(font
					(size 1.27 1.27)
				)
			)
		)
		(duplicate_pad_numbers_are_jumpers no)
		(fp_line
			(start -2.500122 -2.999994)
			(end -2.24409 -2.999994)
			(stroke
				(width 0.1524)
				(type default)
			)
			(layer "F.SilkS")
		)
		(fp_line
			(start -2.500122 -2.529078)
			(end -2.500122 -2.999994)
			(stroke
				(width 0.1524)
				(type default)
			)
			(layer "F.SilkS")
		)
		(fp_line
			(start -2.500122 0.6604)
			(end -2.500122 0.229108)
			(stroke
				(width 0.1524)
				(type default)
			)
			(layer "F.SilkS")
		)
		(fp_line
			(start -2.500122 2.999994)
			(end -2.500122 2.339594)
			(stroke
				(width 0.1524)
				(type default)
			)
			(layer "F.SilkS")
		)
		(fp_line
			(start -2.2987 2.999994)
			(end -2.500122 2.999994)
			(stroke
				(width 0.1524)
				(type default)
			)
			(layer "F.SilkS")
		)
		(fp_line
			(start 2.31394 -2.999994)
			(end 2.500122 -2.999994)
			(stroke
				(width 0.1524)
				(type default)
			)
			(layer "F.SilkS")
		)
		(fp_line
			(start 2.500122 -2.999994)
			(end 2.500122 -2.44348)
			(stroke
				(width 0.1524)
				(type default)
			)
			(layer "F.SilkS")
		)
		(fp_line
			(start 2.500122 2.339594)
			(end 2.500122 2.999994)
			(stroke
				(width 0.1524)
				(type default)
			)
			(layer "F.SilkS")
		)
		(fp_line
			(start 2.500122 2.999994)
			(end 2.2987 2.999994)
			(stroke
				(width 0.1524)
				(type default)
			)
			(layer "F.SilkS")
		)
		(fp_poly
			(pts
				(xy -2.16916 -3.647694) (xy -2.67716 -2.631694) (xy -3.18516 -3.647694)
			)
			(stroke
				(width 0)
				(type default)
			)
			(fill yes)
			(layer "F.SilkS")
		)
		(fp_line
			(start -2.500122 -2.999994)
			(end 2.500122 -2.999994)
			(stroke
				(width 0.1)
				(type default)
			)
			(layer "F.Fab")
		)
		(fp_line
			(start -2.500122 2.999994)
			(end -2.500122 -2.999994)
			(stroke
				(width 0.1)
				(type default)
			)
			(layer "F.Fab")
		)
		(fp_line
			(start 2.500122 -2.999994)
			(end 2.500122 2.999994)
			(stroke
				(width 0.1)
				(type default)
			)
			(layer "F.Fab")
		)
		(fp_line
			(start 2.500122 2.999994)
			(end -2.500122 2.999994)
			(stroke
				(width 0.1)
				(type default)
			)
			(layer "F.Fab")
		)
		(fp_poly
			(pts
				(xy -4.218432 -2.783078) (xy -4.218432 -1.767078) (xy -3.202432 -2.275078)
			)
			(stroke
				(width 0)
				(type default)
			)
			(fill yes)
			(layer "F.Fab")
		)
		(pad "1" smd rect
			(at -2.400046 -2.275078 90)
			(size 0.2286 0.6096)
			(layers "F.Cu" "F.Mask" "F.Paste")
			(net "PVCCFA_EHV_FIVRA_CPU0_VOS1")
		)
		(pad "2" smd rect
			(at -2.400046 -1.82499 90)
			(size 0.2286 0.6096)
			(layers "F.Cu" "F.Mask" "F.Paste")
			(net "GND")
		)
		(pad "3" smd rect
			(at -2.400046 -1.374902 90)
			(size 0.2286 0.6096)
			(layers "F.Cu" "F.Mask" "F.Paste")
			(net "PVCCFA_EHV_FIVRA_CPU0_VDD1")
		)
		(pad "4" smd rect
			(at -2.400046 -0.925068 90)
			(size 0.2286 0.6096)
			(layers "F.Cu" "F.Mask" "F.Paste")
			(net "PVCCFA_EHV_FIVRA_CPU0_PVCC1")
		)
		(pad "5" smd rect
			(at -2.400046 -0.47498 90)
			(size 0.2286 0.6096)
			(layers "F.Cu" "F.Mask" "F.Paste")
			(net "GND")
		)
		(pad "6" smd rect
			(at -2.400046 -0.024892 90)
			(size 0.2286 0.6096)
			(layers "F.Cu" "F.Mask" "F.Paste")
			(net "Net_8517")
		)
		(pad "7_9-20_24" smd circle
			(at 0 1.150112 90)
			(size 0 0)
			(layers "F.Cu" "F.Mask" "F.Paste")
			(net "GND")
		)
		(pad "10_19" smd rect
			(at 0 2.899918 90)
			(size 0.6096 4.318)
			(layers "F.Cu" "F.Mask" "F.Paste")
			(net "SW_PVCCFA_EHV_FIVRA_CPU0_SW1")
		)
		(pad "25_29" smd rect
			(at 1.549908 -1.279906 270)
			(size 2.0574 2.3114)
			(layers "F.Cu" "F.Mask" "F.Paste")
			(net "SW_P12V_PVCCFA_EHV_FIVRA_CPU0_R")
		)
		(pad "30" smd rect
			(at 2.05994 -2.899918)
			(size 0.2286 0.6096)
			(layers "F.Cu" "F.Mask" "F.Paste")
			(net "SW_P12V_PVCCFA_EHV_FIVRA_CPU0_R")
		)
		(pad "31" smd rect
			(at 1.610106 -2.899918)
			(size 0.2286 0.6096)
			(layers "F.Cu" "F.Mask" "F.Paste")
			(net "Net_8518")
		)
		(pad "32" smd rect
			(at 1.160018 -2.899918)
			(size 0.2286 0.6096)
			(layers "F.Cu" "F.Mask" "F.Paste")
			(net "SW_PVCCFA_EHV_FIVRA_CPU0_BOOTR1")
		)
		(pad "33" smd rect
			(at 0.70993 -2.899918)
			(size 0.2286 0.6096)
			(layers "F.Cu" "F.Mask" "F.Paste")
			(net "SW_PVCCFA_EHV_FIVRA_CPU0_BOOT1")
		)
		(pad "34" smd rect
			(at 0.260096 -2.899918)
			(size 0.2286 0.6096)
			(layers "F.Cu" "F.Mask" "F.Paste")
			(net "PVCCFA_EHV_FIVRA_CPU0_PWM1")
		)
		(pad "35" smd rect
			(at -0.189992 -2.899918)
			(size 0.2286 0.6096)
			(layers "F.Cu" "F.Mask" "F.Paste")
			(net "PVCCFA_EHV_FIVRA_CPU0_VDD1")
		)
		(pad "36" smd rect
			(at -0.64008 -2.899918)
			(size 0.2286 0.6096)
			(layers "F.Cu" "F.Mask" "F.Paste")
			(net "PVCCFA_EHV_FIVRA_CPU0_BTSEN")
		)
		(pad "37" smd rect
			(at -1.089914 -2.899918)
			(size 0.2286 0.6096)
			(layers "F.Cu" "F.Mask" "F.Paste")
			(net "PVCCFA_EHV_FIVRA_CPU0_LSET1")
		)
		(pad "38" smd rect
			(at -1.540002 -2.899918)
			(size 0.2286 0.6096)
			(layers "F.Cu" "F.Mask" "F.Paste")
			(net "PVCCFA_EHV_FIVRA_CPU0_IMON1")
		)
		(pad "39" smd rect
			(at -1.99009 -2.899918)
			(size 0.2286 0.6096)
			(layers "F.Cu" "F.Mask" "F.Paste")
			(net "PVCCIN_CPU0_VREF")
		)
		(pad "40" smd rect
			(at -0.87503 -1.27508)
			(size 1.7526 1.9558)
			(layers "F.Cu" "F.Mask" "F.Paste")
			(net "GND")
		)
		(pad "41" smd rect
			(at -1.525016 0.249936 270)
			(size 0.3048 0.4572)
			(layers "F.Cu" "F.Mask" "F.Paste")
			(net "Net_8516")
		)
		(zone
			(layer "F.Cu")
			(hatch none 0.5)
			(connect_pads
				(clearance 0)
			)
			(min_thickness 0.25)
			(keepout
				(tracks not_allowed)
				(vias allowed)
				(pads allowed)
				(copperpour not_allowed)
				(footprints allowed)
			)
			(placement
				(enabled no)
				(sheetname "")
			)
			(fill
				(thermal_gap 0.5)
				(thermal_bridge_width 0.5)
				(island_removal_mode 0)
			)
			(polygon
				(pts
					(xy 413.660336 -359.087674) (xy 413.660336 -359.836974) (xy 418.66058 -359.836974) (xy 418.66058 -359.087674)
					(xy 418.370258 -359.087674) (xy 418.370258 -359.54335) (xy 413.950658 -359.54335) (xy 413.950658 -359.087674)
				)
			)
		)
		(zone
			(layer "F.Cu")
			(hatch none 0.5)
			(connect_pads
				(clearance 0)
			)
			(min_thickness 0.25)
			(keepout
				(tracks not_allowed)
				(vias allowed)
				(pads allowed)
				(copperpour not_allowed)
				(footprints allowed)
			)
			(placement
				(enabled no)
				(sheetname "")
			)
			(fill
				(thermal_gap 0.5)
				(thermal_bridge_width 0.5)
				(island_removal_mode 0)
			)
			(polygon
				(pts
					(xy 414.116012 -362.359956) (xy 414.358328 -362.359956) (xy 414.358328 -362.334048) (xy 415.174684 -362.334048)
					(xy 415.174684 -362.009182) (xy 415.209736 -362.009182) (xy 415.209736 -361.387644) (xy 415.16046 -361.338368)
					(xy 413.660336 -361.338368) (xy 413.660336 -361.79506) (xy 414.356042 -361.79506) (xy 414.356042 -361.634532)
					(xy 414.914842 -361.634532) (xy 414.914842 -362.040932) (xy 414.356042 -362.040932) (xy 414.356042 -361.82046)
					(xy 413.660336 -361.82046) (xy 413.660336 -361.94746) (xy 414.116012 -361.94746)
				)
			)
		)
	)
	(footprint ""
		(layer "F.Cu")
		(at 182.964582 -426.8216 180)
		(property "Reference" "R2950"
			(at 0 0 180)
			(layer "F.SilkS")
			(hide yes)
			(effects
				(font
					(size 1.27 1.27)
				)
			)
		)
		(property "Value" ""
			(at 0 0 180)
			(layer "F.Fab")
			(effects
				(font
					(size 1.27 1.27)
				)
			)
		)
		(duplicate_pad_numbers_are_jumpers no)
		(fp_line
			(start 0.7874 0.4064)
			(end -0.7874 0.4064)
			(stroke
				(width 0.1524)
				(type default)
			)
			(layer "F.SilkS")
		)
		(fp_line
			(start 0.7874 -0.4064)
			(end 0.7874 0.4064)
			(stroke
				(width 0.1524)
				(type default)
			)
			(layer "F.SilkS")
		)
		(fp_line
			(start -0.7874 0.4064)
			(end -0.7874 -0.4064)
			(stroke
				(width 0.1524)
				(type default)
			)
			(layer "F.SilkS")
		)
		(fp_line
			(start -0.7874 -0.4064)
			(end 0.7874 -0.4064)
			(stroke
				(width 0.1524)
				(type default)
			)
			(layer "F.SilkS")
		)
		(fp_line
			(start 0.67945 0.3048)
			(end 0.120396 0.3048)
			(stroke
				(width 0.1)
				(type default)
			)
			(layer "F.Fab")
		)
		(fp_line
			(start 0.67945 -0.3048)
			(end 0.67945 0.3048)
			(stroke
				(width 0.1)
				(type default)
			)
			(layer "F.Fab")
		)
		(fp_line
			(start 0.12065 -0.2794)
			(end 0.12065 -0.3048)
			(stroke
				(width 0.1)
				(type default)
			)
			(layer "F.Fab")
		)
		(fp_line
			(start 0.12065 -0.3048)
			(end 0.67945 -0.3048)
			(stroke
				(width 0.1)
				(type default)
			)
			(layer "F.Fab")
		)
		(fp_line
			(start 0.120396 0.3048)
			(end 0.120396 0.2794)
			(stroke
				(width 0.1)
				(type default)
			)
			(layer "F.Fab")
		)
		(fp_line
			(start 0.120396 0.2794)
			(end -0.12065 0.2794)
			(stroke
				(width 0.1)
				(type default)
			)
			(layer "F.Fab")
		)
		(fp_line
			(start -0.12065 0.3048)
			(end -0.67945 0.3048)
			(stroke
				(width 0.1)
				(type default)
			)
			(layer "F.Fab")
		)
		(fp_line
			(start -0.12065 0.2794)
			(end -0.12065 0.3048)
			(stroke
				(width 0.1)
				(type default)
			)
			(layer "F.Fab")
		)
		(fp_line
			(start -0.12065 -0.2794)
			(end 0.12065 -0.2794)
			(stroke
				(width 0.1)
				(type default)
			)
			(layer "F.Fab")
		)
		(fp_line
			(start -0.12065 -0.305054)
			(end -0.12065 -0.2794)
			(stroke
				(width 0.1)
				(type default)
			)
			(layer "F.Fab")
		)
		(fp_line
			(start -0.67945 0.3048)
			(end -0.67945 -0.305054)
			(stroke
				(width 0.1)
				(type default)
			)
			(layer "F.Fab")
		)
		(fp_line
			(start -0.67945 -0.305054)
			(end -0.12065 -0.305054)
			(stroke
				(width 0.1)
				(type default)
			)
			(layer "F.Fab")
		)
		(pad "1" smd circle
			(at -0.40005 0 180)
			(size 0 0)
			(layers "F.Cu" "F.Mask" "F.Paste")
			(net "P3V3_AUX")
		)
		(pad "2" smd circle
			(at 0.40005 0 180)
			(size 0 0)
			(layers "F.Cu" "F.Mask" "F.Paste")
			(net "FM_PDB_BUF_EN_R")
		)
	)
	(footprint ""
		(layer "F.Cu")
		(at 160.83788 -121.376948 180)
		(property "Reference" "R1405"
			(at 0 0 180)
			(layer "F.SilkS")
			(hide yes)
			(effects
				(font
					(size 1.27 1.27)
				)
			)
		)
		(property "Value" ""
			(at 0 0 180)
			(layer "F.Fab")
			(effects
				(font
					(size 1.27 1.27)
				)
			)
		)
		(duplicate_pad_numbers_are_jumpers no)
		(fp_line
			(start 0.7874 0.4064)
			(end -0.7874 0.4064)
			(stroke
				(width 0.1524)
				(type default)
			)
			(layer "F.SilkS")
		)
		(fp_line
			(start 0.7874 -0.4064)
			(end 0.7874 0.4064)
			(stroke
				(width 0.1524)
				(type default)
			)
			(layer "F.SilkS")
		)
		(fp_line
			(start -0.7874 0.4064)
			(end -0.7874 -0.4064)
			(stroke
				(width 0.1524)
				(type default)
			)
			(layer "F.SilkS")
		)
		(fp_line
			(start -0.7874 -0.4064)
			(end 0.7874 -0.4064)
			(stroke
				(width 0.1524)
				(type default)
			)
			(layer "F.SilkS")
		)
		(fp_line
			(start 0.67945 0.3048)
			(end 0.120396 0.3048)
			(stroke
				(width 0.1)
				(type default)
			)
			(layer "F.Fab")
		)
		(fp_line
			(start 0.67945 -0.3048)
			(end 0.67945 0.3048)
			(stroke
				(width 0.1)
				(type default)
			)
			(layer "F.Fab")
		)
		(fp_line
			(start 0.12065 -0.2794)
			(end 0.12065 -0.3048)
			(stroke
				(width 0.1)
				(type default)
			)
			(layer "F.Fab")
		)
		(fp_line
			(start 0.12065 -0.3048)
			(end 0.67945 -0.3048)
			(stroke
				(width 0.1)
				(type default)
			)
			(layer "F.Fab")
		)
		(fp_line
			(start 0.120396 0.3048)
			(end 0.120396 0.2794)
			(stroke
				(width 0.1)
				(type default)
			)
			(layer "F.Fab")
		)
		(fp_line
			(start 0.120396 0.2794)
			(end -0.12065 0.2794)
			(stroke
				(width 0.1)
				(type default)
			)
			(layer "F.Fab")
		)
		(fp_line
			(start -0.12065 0.3048)
			(end -0.67945 0.3048)
			(stroke
				(width 0.1)
				(type default)
			)
			(layer "F.Fab")
		)
		(fp_line
			(start -0.12065 0.2794)
			(end -0.12065 0.3048)
			(stroke
				(width 0.1)
				(type default)
			)
			(layer "F.Fab")
		)
		(fp_line
			(start -0.12065 -0.2794)
			(end 0.12065 -0.2794)
			(stroke
				(width 0.1)
				(type default)
			)
			(layer "F.Fab")
		)
		(fp_line
			(start -0.12065 -0.305054)
			(end -0.12065 -0.2794)
			(stroke
				(width 0.1)
				(type default)
			)
			(layer "F.Fab")
		)
		(fp_line
			(start -0.67945 0.3048)
			(end -0.67945 -0.305054)
			(stroke
				(width 0.1)
				(type default)
			)
			(layer "F.Fab")
		)
		(fp_line
			(start -0.67945 -0.305054)
			(end -0.12065 -0.305054)
			(stroke
				(width 0.1)
				(type default)
			)
			(layer "F.Fab")
		)
		(pad "1" smd circle
			(at -0.40005 0 180)
			(size 0 0)
			(layers "F.Cu" "F.Mask" "F.Paste")
			(net "FM_PVCCIN_CPU0_R_EN")
		)
		(pad "2" smd circle
			(at 0.40005 0 180)
			(size 0 0)
			(layers "F.Cu" "F.Mask" "F.Paste")
			(net "GND")
		)
	)
)
